# BASEBOARD_FAB2 (Tioga Pass) — schematic netlist excerpt (pin names and nets, part order shuffled) for the footprints in the layout excerpt that follows; sources: Cadence DE-HDL packaged netlist, KiCad conversion of Wiwynn_Tioga_Pass_MB.brd

CR1F5  DIODE  MBRS340T3G EMPTY  pkg SM  page 200 : C = P12V_STBY ; A = GND
R9W16  RES  2.0K 1% CHIP  pkg 0402  page 248 : A = P3V3_STBY ; B = SMB_PEHPCPU0_STBY_LVC3_R_SDA
C1G27  CAP_A  1.0UF 6.3V 10% X6S  pkg 0402V  page 223 : A = VR_PVDDQ_GHJ_VDD ; B = GND

(kicad_pcb
	(version 20260206)
	(generator "pcbnew")
	(generator_version "10.0")
	(general
		(thickness 1.6)
		(legacy_teardrops no)
	)
	(paper "A4")
	(title_block
		(title "Wiwynn_Tioga_Pass_MB.brd")
		(comment 1 "Tioga Pass / footprints 1534-1536 of 4770")
	)
	(layers
		(0 "F.Cu" signal "TOP")
		(4 "In1.Cu" signal "L2GND")
		(6 "In2.Cu" signal "L3")
		(8 "In3.Cu" signal "L4GND")
		(10 "In4.Cu" signal "L5")
		(12 "In5.Cu" signal "L6GND")
		(14 "In6.Cu" signal "L7VCC")
		(16 "In7.Cu" signal "L8VCC")
		(18 "In8.Cu" signal "L9GND")
		(20 "In9.Cu" signal "L10")
		(22 "In10.Cu" signal "L11GND")
		(24 "In11.Cu" signal "L12")
		(26 "In12.Cu" signal "L13GND")
		(2 "B.Cu" signal "BOTTOM")
		(9 "F.Adhes" user "F.Adhesive")
		(11 "B.Adhes" user "B.Adhesive")
		(13 "F.Paste" user "Package Geometry/Pastemask Top")
		(15 "B.Paste" user "Package Geometry/Pastemask Bottom")
		(5 "F.SilkS" user "Ref Des/Silkscreen Top")
		(7 "B.SilkS" user "Ref Des/Silkscreen Bottom")
		(1 "F.Mask" user "Board Geometry/Soldermask Top")
		(3 "B.Mask" user "Board Geometry/Soldermask Bottom")
		(17 "Dwgs.User" user "User.Drawings")
		(19 "Cmts.User" user "User.Comments")
		(21 "Eco1.User" user "User.Eco1")
		(23 "Eco2.User" user "User.Eco2")
		(25 "Edge.Cuts" user "Board Geometry/Outline")
		(27 "Margin" user)
		(31 "F.CrtYd" user "Package Geometry/Place Bound Top")
		(29 "B.CrtYd" user "Package Geometry/Place Bound Bottom")
		(35 "F.Fab" user "Ref Des/Assembly Top")
		(33 "B.Fab" user "Ref Des/Assembly Bottom")
	)
	(footprint ""
		(layer "F.Cu")
		(at 422.2115 -113.03 -90)
		(property "Reference" "R9W16"
			(at -0.8382 -0.67818 270)
			(unlocked yes)
			(layer "F.SilkS")
			(effects
				(font
					(size 0.4064 0.254)
					(thickness 0.1524)
				)
				(justify left)
			)
		)
		(property "Value" ""
			(at 0 0 270)
			(layer "F.Fab")
			(effects
				(font
					(size 1.27 1.27)
				)
			)
		)
		(duplicate_pad_numbers_are_jumpers no)
		(fp_poly
			(pts
				(xy -0.2794 -0.1016) (xy 0.2794 -0.1016) (xy 0.2794 0.9906) (xy -0.2794 0.9906)
			)
			(stroke
				(width 0)
				(type default)
			)
			(fill no)
			(layer "F.CrtYd")
		)
		(fp_line
			(start -0.2794 0.9906)
			(end 0.2794 0.9906)
			(stroke
				(width 0.1)
				(type default)
			)
			(layer "F.Fab")
		)
		(fp_line
			(start 0.2794 0.9906)
			(end 0.2794 -0.1016)
			(stroke
				(width 0.1)
				(type default)
			)
			(layer "F.Fab")
		)
		(fp_line
			(start -0.2794 -0.1016)
			(end -0.2794 0.9906)
			(stroke
				(width 0.1)
				(type default)
			)
			(layer "F.Fab")
		)
		(fp_line
			(start 0.2794 -0.1016)
			(end -0.2794 -0.1016)
			(stroke
				(width 0.1)
				(type default)
			)
			(layer "F.Fab")
		)
		(pad "1" smd rect
			(at 0 0 270)
			(size 0.508 0.508)
			(layers "F.Cu" "F.Mask" "F.Paste")
			(net "P3V3_STBY")
		)
		(pad "2" smd rect
			(at 0 0.889 270)
			(size 0.508 0.508)
			(layers "F.Cu" "F.Mask" "F.Paste")
			(net "SMB_PEHPCPU0_STBY_LVC3_R_SDA")
		)
		(zone
			(layer "F.Cu")
			(hatch none 0.5)
			(connect_pads
				(clearance 0)
			)
			(min_thickness 0.25)
			(keepout
				(tracks not_allowed)
				(vias allowed)
				(pads allowed)
				(copperpour not_allowed)
				(footprints allowed)
			)
			(placement
				(enabled no)
				(sheetname "")
			)
			(fill
				(thermal_gap 0.5)
				(thermal_bridge_width 0.5)
				(island_removal_mode 0)
			)
			(polygon
				(pts
					(xy 421.5765 -113.284) (xy 421.5765 -112.776) (xy 421.9575 -112.776) (xy 421.9575 -113.284)
				)
			)
		)
		(zone
			(layer "F.Cu")
			(hatch none 0.5)
			(connect_pads
				(clearance 0)
			)
			(min_thickness 0.25)
			(keepout
				(tracks allowed)
				(vias not_allowed)
				(pads allowed)
				(copperpour not_allowed)
				(footprints allowed)
			)
			(placement
				(enabled no)
				(sheetname "")
			)
			(fill
				(thermal_gap 0.5)
				(thermal_bridge_width 0.5)
				(island_removal_mode 0)
			)
			(polygon
				(pts
					(xy 421.9575 -113.284) (xy 421.9575 -112.776) (xy 421.5765 -112.776) (xy 421.5765 -113.284)
				)
			)
		)
	)
	(footprint ""
		(layer "F.Cu")
		(at 14.36116 4.269232)
		(property "Reference" "C1G27"
			(at 0 0 0)
			(layer "F.SilkS")
			(hide yes)
			(effects
				(font
					(size 1.27 1.27)
				)
			)
		)
		(property "Value" ""
			(at 0 0 0)
			(layer "F.Fab")
			(effects
				(font
					(size 1.27 1.27)
				)
			)
		)
		(duplicate_pad_numbers_are_jumpers no)
		(fp_poly
			(pts
				(xy 0.3048 -0.1016) (xy 0.3048 0.9906) (xy -0.3048 0.9906) (xy -0.3048 -0.1016)
			)
			(stroke
				(width 0)
				(type default)
			)
			(fill no)
			(layer "F.CrtYd")
		)
		(fp_line
			(start -0.3048 -0.1016)
			(end -0.3048 0.9906)
			(stroke
				(width 0.1)
				(type default)
			)
			(layer "F.Fab")
		)
		(fp_line
			(start -0.3048 0.9906)
			(end 0.3048 0.9906)
			(stroke
				(width 0.1)
				(type default)
			)
			(layer "F.Fab")
		)
		(fp_line
			(start 0.3048 -0.1016)
			(end -0.3048 -0.1016)
			(stroke
				(width 0.1)
				(type default)
			)
			(layer "F.Fab")
		)
		(fp_line
			(start 0.3048 0.9906)
			(end 0.3048 -0.1016)
			(stroke
				(width 0.1)
				(type default)
			)
			(layer "F.Fab")
		)
		(pad "1" smd rect
			(at 0 0)
			(size 0.508 0.508)
			(layers "F.Cu" "F.Mask" "F.Paste")
			(net "VR_PVDDQ_GHJ_VDD")
		)
		(pad "2" smd rect
			(at 0 0.889)
			(size 0.508 0.508)
			(layers "F.Cu" "F.Mask" "F.Paste")
			(net "GND")
		)
		(zone
			(layer "F.Cu")
			(hatch none 0.5)
			(connect_pads
				(clearance 0)
			)
			(min_thickness 0.25)
			(keepout
				(tracks allowed)
				(vias not_allowed)
				(pads allowed)
				(copperpour not_allowed)
				(footprints allowed)
			)
			(placement
				(enabled no)
				(sheetname "")
			)
			(fill
				(thermal_gap 0.5)
				(thermal_bridge_width 0.5)
				(island_removal_mode 0)
			)
			(polygon
				(pts
					(xy 14.10716 4.523232) (xy 14.61516 4.523232) (xy 14.61516 4.904232) (xy 14.10716 4.904232)
				)
			)
		)
		(zone
			(layer "F.Cu")
			(hatch none 0.5)
			(connect_pads
				(clearance 0)
			)
			(min_thickness 0.25)
			(keepout
				(tracks not_allowed)
				(vias allowed)
				(pads allowed)
				(copperpour not_allowed)
				(footprints allowed)
			)
			(placement
				(enabled no)
				(sheetname "")
			)
			(fill
				(thermal_gap 0.5)
				(thermal_bridge_width 0.5)
				(island_removal_mode 0)
			)
			(polygon
				(pts
					(xy 14.10716 4.904232) (xy 14.61516 4.904232) (xy 14.61516 4.523232) (xy 14.10716 4.523232)
				)
			)
		)
	)
	(footprint ""
		(layer "F.Cu")
		(at 38.07968 -34.912808)
		(property "Reference" "CR1F5"
			(at 4.29133 1.397 270)
			(unlocked yes)
			(layer "F.SilkS")
			(effects
				(font
					(size 0.7874 0.5842)
					(thickness 0.1524)
				)
				(justify left)
			)
		)
		(property "Value" ""
			(at 0 0 0)
			(layer "F.Fab")
			(effects
				(font
					(size 1.27 1.27)
				)
			)
		)
		(duplicate_pad_numbers_are_jumpers no)
		(fp_line
			(start -3.111754 7.5946)
			(end -3.1115 -0.228346)
			(stroke
				(width 0.1524)
				(type default)
			)
			(layer "F.SilkS")
		)
		(fp_line
			(start -3.111754 7.5946)
			(end -1.9431 7.5946)
			(stroke
				(width 0.1524)
				(type default)
			)
			(layer "F.SilkS")
		)
		(fp_line
			(start -3.1115 -0.228346)
			(end -1.9431 -0.2286)
			(stroke
				(width 0.1524)
				(type default)
			)
			(layer "F.SilkS")
		)
		(fp_line
			(start 1.9431 -0.2286)
			(end 3.1115 -0.228346)
			(stroke
				(width 0.1524)
				(type default)
			)
			(layer "F.SilkS")
		)
		(fp_line
			(start 1.9431 7.5946)
			(end 3.111754 7.5946)
			(stroke
				(width 0.1524)
				(type default)
			)
			(layer "F.SilkS")
		)
		(fp_line
			(start 3.1115 -0.228346)
			(end 3.111754 7.5946)
			(stroke
				(width 0.1524)
				(type default)
			)
			(layer "F.SilkS")
		)
		(fp_circle
			(center -2.413 -1.016)
			(end -2.286 -1.016)
			(stroke
				(width 0.254)
				(type default)
			)
			(fill no)
			(layer "F.SilkS")
		)
		(fp_poly
			(pts
				(xy -3.111754 7.5946) (xy 3.111754 7.5946) (xy 3.1115 -0.228346) (xy -3.1115 -0.228346)
			)
			(stroke
				(width 0)
				(type default)
			)
			(fill no)
			(layer "F.CrtYd")
		)
		(fp_line
			(start -3.111754 7.5946)
			(end 3.111754 7.5946)
			(stroke
				(width 0.1)
				(type default)
			)
			(layer "F.Fab")
		)
		(fp_line
			(start -3.1115 -0.228346)
			(end -3.111754 7.5946)
			(stroke
				(width 0.1)
				(type default)
			)
			(layer "F.Fab")
		)
		(fp_line
			(start 3.1115 -0.228346)
			(end -3.1115 -0.228346)
			(stroke
				(width 0.1)
				(type default)
			)
			(layer "F.Fab")
		)
		(fp_line
			(start 3.111754 7.5946)
			(end 3.1115 -0.228346)
			(stroke
				(width 0.1)
				(type default)
			)
			(layer "F.Fab")
		)
		(fp_circle
			(center -2.413 -0.9906)
			(end -2.286 -0.9906)
			(stroke
				(width 0.254)
				(type default)
			)
			(fill no)
			(layer "F.Fab")
		)
		(pad "1" smd rect
			(at 0 0)
			(size 3.048 2.286)
			(layers "F.Cu" "F.Mask" "F.Paste")
			(net "P12V_STBY")
		)
		(pad "2" smd rect
			(at 0 7.366)
			(size 3.048 2.286)
			(layers "F.Cu" "F.Mask" "F.Paste")
			(net "GND")
		)
	)
)
